# BASEBOARD_FAB2 (Tioga Pass) — schematic parts with pin connectivity, parts 4255–4428 of 4751; source: Cadence DE-HDL packaged netlist (pstxprt.dat, pstxnet.dat, pstchip.dat)

R12W30  RES  0.0 5% EMPTY  pkg 0402  page 218 : 1 = TP_PVDDQ_DEF_MP2 ; 2 = PWRGD_PVDDQ_DEF
R12W31  RES  0.0 5% CHIP  pkg 0402  page 223 : 1 = PU_VR_PVDDQ_GHJ_FAULT1 ; 2 = PWRGD_PVDDQ_GHJ
R12W32  RES  0.0 5% EMPTY  pkg 0402  page 223 : 1 = TP_PVDDQ_GHJ_MP1 ; 2 = PWRGD_PVDDQ_GHJ
R12W33  RES  0.0 5% EMPTY  pkg 0402  page 223 : 1 = TP_PVDDQ_GHJ_MP2 ; 2 = PWRGD_PVDDQ_GHJ
R12W34  RES  0.0 5% CHIP  pkg 0402  page 226 : 1 = PU_VR_PVDDQ_KLM_FAULT1 ; 2 = PWRGD_PVDDQ_KLM
R12W35  RES  0.0 5% EMPTY  pkg 0402  page 226 : 1 = NC_PVDDQ_KLM_GP1 ; 2 = PWRGD_PVDDQ_KLM
R12W36  RES  0.0 5% EMPTY  pkg 0402  page 226 : 1 = NC_PVDDQ_KLM_GP0 ; 2 = PWRGD_PVDDQ_KLM
R24W1  RES  3.3K 5% CHIP  pkg 0402  page 138 : 1 = P3V3_STBY ; 2 = SMB_SLOTX24_PCH_STBY_LVC3_SDA
R24W2  RES  3.3K 5% CHIP  pkg 0402  page 138 : 1 = P3V3_STBY ; 2 = SMB_SLOTX24_PCH_STBY_LVC3_SCL
R25W1  120R2F-GP  1%  pkg RCL_GP  page 151 : 1 = GND ; 2 = BMC_M_CKE
R25W2  120R2F-GP  1%  pkg RCL_GP  page 151 : 1 = GND ; 2 = BMC_M_ODT
R25W3  120R2F-GP  1%  pkg RCL_GP  page 151 : 1 = GND ; 2 = BMC_M_RST_N
R25W4  120R2F-GP  1%  pkg RCL_GP  page 151 : 1 = GND ; 2 = BMC_M_MALERT_N
R25W5  120R2F-GP  1%  pkg RCL_GP  page 151 : 1 = GND ; 2 = BMC_M_CS_N
R25W6  120R2F-GP  1%  pkg RCL_GP  page 151 : 1 = GND ; 2 = BMC_M_RAS_N
R25W7  120R2F-GP  1%  pkg RCL_GP  page 151 : 1 = GND ; 2 = BMC_M_CAS_N
R25W8  120R2F-GP  1%  pkg RCL_GP  page 151 : 1 = GND ; 2 = BMC_M_WE_N
R25W9  120R2F-GP  1%  pkg RCL_GP  page 151 : 1 = GND ; 2 = BMC_M_BA0
R25W10  120R2F-GP  1%  pkg RCL_GP  page 151 : 1 = GND ; 2 = BMC_M_BA1
R25W11  120R2F-GP  1%  pkg RCL_GP  page 151 : 1 = GND ; 2 = BMC_M_BG0
R25W12  120R2F-GP  1%  pkg RCL_GP  page 151 : 1 = GND ; 2 = BMC_M_A0
R25W13  120R2F-GP  1%  pkg RCL_GP  page 151 : 1 = GND ; 2 = BMC_M_A1
R25W14  120R2F-GP  1%  pkg RCL_GP  page 151 : 1 = GND ; 2 = BMC_M_A2
R25W15  120R2F-GP  1%  pkg RCL_GP  page 151 : 1 = GND ; 2 = BMC_M_A3
R25W16  120R2F-GP  1%  pkg RCL_GP  page 151 : 1 = GND ; 2 = BMC_M_A4
R25W17  120R2F-GP  1%  pkg RCL_GP  page 151 : 1 = GND ; 2 = BMC_M_A5
R25W18  120R2F-GP  1%  pkg RCL_GP  page 151 : 1 = GND ; 2 = BMC_M_A6
R25W19  120R2F-GP  1%  pkg RCL_GP  page 151 : 1 = GND ; 2 = BMC_M_A7
R25W20  120R2F-GP  1%  pkg RCL_GP  page 151 : 1 = GND ; 2 = BMC_M_A8
R25W21  120R2F-GP  1%  pkg RCL_GP  page 151 : 1 = GND ; 2 = BMC_M_A9
R25W22  120R2F-GP  1%  pkg RCL_GP  page 151 : 1 = GND ; 2 = BMC_M_A10
R25W23  120R2F-GP  1%  pkg RCL_GP  page 151 : 1 = GND ; 2 = BMC_M_A11
R25W24  120R2F-GP  1%  pkg RCL_GP  page 151 : 1 = GND ; 2 = BMC_M_A12
R25W25  120R2F-GP  1%  pkg RCL_GP  page 151 : 1 = GND ; 2 = BMC_M_A13
R25W26  120R2F-GP  1%  pkg RCL_GP  page 151 : 1 = GND ; 2 = BMC_M_MACT_N
R25W27  120R2F-GP  1%  pkg RCL_GP  page 151 : 1 = BMC_M_CKE ; 2 = P1V2_AUX_BMC
R25W28  120R2F-GP  1%  pkg RCL_GP  page 151 : 1 = BMC_M_ODT ; 2 = P1V2_AUX_BMC
R25W29  120R2F-GP  1%  pkg RCL_GP  page 151 : 1 = BMC_M_RST_N ; 2 = P1V2_AUX_BMC
R25W30  RES  2.7K 1% CHIP  pkg 0402  page 151 : 1 = BMC_M_MALERT_N ; 2 = P1V2_AUX_BMC
R25W31  120R2F-GP  1%  pkg RCL_GP  page 151 : 1 = BMC_M_CS_N ; 2 = P1V2_AUX_BMC
R25W32  120R2F-GP  1%  pkg RCL_GP  page 151 : 1 = BMC_M_RAS_N ; 2 = P1V2_AUX_BMC
R25W33  120R2F-GP  1%  pkg RCL_GP  page 151 : 1 = BMC_M_CAS_N ; 2 = P1V2_AUX_BMC
R25W34  120R2F-GP  1%  pkg RCL_GP  page 151 : 1 = BMC_M_WE_N ; 2 = P1V2_AUX_BMC
R25W35  120R2F-GP  1%  pkg RCL_GP  page 151 : 1 = BMC_M_BA0 ; 2 = P1V2_AUX_BMC
R25W36  120R2F-GP  1%  pkg RCL_GP  page 151 : 1 = BMC_M_BA1 ; 2 = P1V2_AUX_BMC
R25W37  120R2F-GP  1%  pkg RCL_GP  page 151 : 1 = BMC_M_BG0 ; 2 = P1V2_AUX_BMC
R25W38  120R2F-GP  1%  pkg RCL_GP  page 151 : 1 = BMC_M_A0 ; 2 = P1V2_AUX_BMC
R25W39  120R2F-GP  1%  pkg RCL_GP  page 151 : 1 = BMC_M_A1 ; 2 = P1V2_AUX_BMC
R25W40  120R2F-GP  1%  pkg RCL_GP  page 151 : 1 = BMC_M_A2 ; 2 = P1V2_AUX_BMC
R25W41  120R2F-GP  1%  pkg RCL_GP  page 151 : 1 = BMC_M_A3 ; 2 = P1V2_AUX_BMC
R25W42  120R2F-GP  1%  pkg RCL_GP  page 151 : 1 = BMC_M_A4 ; 2 = P1V2_AUX_BMC
R25W43  120R2F-GP  1%  pkg RCL_GP  page 151 : 1 = BMC_M_A5 ; 2 = P1V2_AUX_BMC
R25W44  120R2F-GP  1%  pkg RCL_GP  page 151 : 1 = BMC_M_A6 ; 2 = P1V2_AUX_BMC
R25W45  120R2F-GP  1%  pkg RCL_GP  page 151 : 1 = BMC_M_A7 ; 2 = P1V2_AUX_BMC
R25W46  120R2F-GP  1%  pkg RCL_GP  page 151 : 1 = BMC_M_A8 ; 2 = P1V2_AUX_BMC
R25W47  120R2F-GP  1%  pkg RCL_GP  page 151 : 1 = BMC_M_A9 ; 2 = P1V2_AUX_BMC
R25W48  120R2F-GP  1%  pkg RCL_GP  page 151 : 1 = BMC_M_A10 ; 2 = P1V2_AUX_BMC
R25W49  120R2F-GP  1%  pkg RCL_GP  page 151 : 1 = BMC_M_A11 ; 2 = P1V2_AUX_BMC
R25W50  120R2F-GP  1%  pkg RCL_GP  page 151 : 1 = BMC_M_A12 ; 2 = P1V2_AUX_BMC
R25W51  120R2F-GP  1%  pkg RCL_GP  page 151 : 1 = BMC_M_A13 ; 2 = P1V2_AUX_BMC
R25W52  120R2F-GP  1%  pkg RCL_GP  page 151 : 1 = BMC_M_MACT_N ; 2 = P1V2_AUX_BMC
R25W57  RES  49.9K 1% CHIP  pkg 0402  page 147 : 1 = PD_ADCREXT ; 2 = GND
R25W58  18KR2F-GP  1%  pkg RCL_GP  page 144 : 1 = A_DACRSET ; 2 = GND
R25W59  RES  0.0 5% CHIP  pkg 0402  page 148 : 1 = P3V3_STBY ; 2 = VCCBAT_TW12
R25W60  RES  100.0K 1% CHIP  pkg 0402  page 145 : 1 = CLK_100M_BMC_PE_R_DN ; 2 = GND
R25W61  RES  100.0K 1% CHIP  pkg 0402  page 145 : 1 = CLK_100M_BMC_PE_R_DP ; 2 = GND
R25W62  RES  100.0K 1% CHIP  pkg 0402  page 145 : 1 = RST_PLTRST_BUF_N_R ; 2 = GND
R25W63  RES  100.0K 1% CHIP  pkg 0402  page 146 : 1 = FM_PE_BMC_WAKE_N ; 2 = GND
R25W64  RES  100.0K 1% CHIP  pkg 0402  page 145 : 1 = P2E_SSB_BMC_TX_C_DP ; 2 = GND
R25W65  RES  100.0K 1% CHIP  pkg 0402  page 145 : 1 = P2E_SSB_BMC_TX_C_DN ; 2 = GND
R25W66  RES  100.0K 1% CHIP  pkg 0402  page 146 : 1 = CLK_24M_BMC_LPC ; 2 = GND
R25W67  200R2F-L1-GP  1%  pkg SMD-RG4  page 145 : 1 = PD_PEREXT ; 2 = GND
R25W68  RES  33.2 1% CHIP  pkg 0402  page 146 : 1 = LPC_LAD3_IO3 ; 2 = LPC_LAD3_IO3_R
R25W69  RES  33.2 1% CHIP  pkg 0402  page 146 : 1 = LPC_LAD1_IO1 ; 2 = LPC_LAD1_IO1_R
R25W70  RES  33.2 1% CHIP  pkg 0402  page 144 : 1 = FM_CPU0_FIVR_FAULT_LVT3_R_N ; 2 = FM_CPU0_FIVR_FAULT_LVT3_N
R25W72  RES  33.2 1% CHIP  pkg 0402  page 146 : 1 = LPC_LFRAME_N_CS0_N ; 2 = LPC_LFRAME_N_CS0_R_N
R25W73  RES  33.2 1% CHIP  pkg 0402  page 146 : 1 = IRQ_LPC_SERIRQ_N ; 2 = IRQ_LPC_SERIRQ_R
R25W74  RES  0.0 5% CHIP  pkg 0402  page 146 : 1 = RST_PLTRST_BUF_N ; 2 = RST_BMC_LVC3_N
R25W75  RES  33.2 1% CHIP  pkg 0402  page 144 : 1 = FM_CPU1_FIVR_FAULT_LVT3_R_N ; 2 = FM_CPU1_FIVR_FAULT_LVT3_N
R25W78  RES  22.1 1.0% CHIP  pkg 0402  page 146 : 1 = SPI_BMC_BT_CS_R_N ; 2 = SPI_BMC_BT_CS_N
R25W79  RES  10.0K 1% CHIP  pkg 0402  page 147 : 1 = P3V3_STBY ; 2 = RMII_SPRNGVLLE_BMC_PCH_RXD0
R25W80  RES  10.0K 1% CHIP  pkg 0402  page 147 : 1 = P3V3_STBY ; 2 = RMII_SPRNGVLLE_BMC_PCH_RXD1
R25W81  RES  33.2 1% CHIP  pkg 0402  page 146 : 1 = SPI_BMC_BT_CLK ; 2 = SPI_BMC_BT_CLK_R
R25W82  RES  33.2 1% CHIP  pkg 0402  page 146 : 1 = SPI_BMC_BT_DO ; 2 = SPI_BMC_BT_DO_R
R25W83  RES  0.0 5% CHIP  pkg 0402  page 146 : 1 = FM_BMC_NMI_N ; 2 = FM_BMC_NMI_N_R
R25W85  RES  22.1 1.0% CHIP  pkg 0402  page 147 : 1 = RMII_BMC_OCP_TXEN_R ; 2 = RMII_BMC_OCP_TXEN
R25W86  RES  22.1 1.0% CHIP  pkg 0402  page 147 : 1 = RMII_BMC_OCP_TXD0_R ; 2 = RMII_BMC_OCP_TXD0
R25W87  RES  22.1 1.0% CHIP  pkg 0402  page 147 : 1 = RMII_BMC_OCP_TXD1_R ; 2 = RMII_BMC_OCP_TXD1
R25W88  RES  22.1 1.0% CHIP  pkg 0402  page 147 : 1 = RMII_BMC_SPRNGVLLE_TXEN_R ; 2 = RMII_BMC_PCH_SPRNGVLLE_TXEN
R25W89  RES  22.1 1.0% CHIP  pkg 0402  page 147 : 1 = RMII_BMC_PCH_SPRNGVLLE_TXD0_R ; 2 = RMII_BMC_PCH_SPRNGVLLE_TXD0
R25W90  RES  22.1 1.0% CHIP  pkg 0402  page 147 : 1 = RMII_BMC_PCH_SPRNGVLLE_TXD1_R ; 2 = RMII_BMC_PCH_SPRNGVLLE_TXD1
R25W93  RES  0 5.0% CHIP  pkg 0603  page 149 : 1 = P3V3_STBY ; 2 = VCC_DACAV3V3
R25W94  RES  4.75K 1% CHIP  pkg 0402  page 137 : 1 = GND ; 2 = PD_SPI_BMC_BT_CS0_N
R25W95  RES  4.75K 1% CHIP  pkg 0402  page 150 : 1 = P3V3_STBY ; 2 = SPI_BMC_BT_CLK
R25W96  RES  4.75K 1% CHIP  pkg 0402  page 150 : 1 = P3V3_STBY ; 2 = SPI_BMC_BT_DO
R25W97  RES  4.75K 1% EMPTY  pkg 0402  page 150 : 1 = P3V3_STBY ; 2 = SPI_BMC_BT_DI
R25W98  RES  4.75K 1% EMPTY  pkg 0402  page 150 : 1 = P3V3_STBY ; 2 = BMC_STRAP_BIT3
R25W99  RES  4.75K 1% EMPTY  pkg 0402  page 150 : 1 = P3V3_STBY ; 2 = BMC_STRAP_BIT5
R25W100  RES  4.75K 1% CHIP  pkg 0402  page 150 : 1 = P3V3_STBY ; 2 = GPIOS7
R25W101  RES  4.75K 1% EMPTY  pkg 0402  page 150 : 1 = P3V3_STBY ; 2 = BMC_STRAP_BIT17
R25W102  RES  4.75K 1% EMPTY  pkg 0402  page 150 : 1 = P3V3_STBY ; 2 = BMC_STRAP_BIT18
R25W103  RES  4.75K 1% EMPTY  pkg 0402  page 150 : 1 = P3V3_STBY ; 2 = BMC_STRAP_BIT20
R25W104  RES  4.75K 1% CHIP  pkg 0402  page 150 : 1 = P3V3_STBY ; 2 = BMC_STRAP_BIT27
R25W105  RES  4.75K 1% EMPTY  pkg 0402  page 150 : 1 = P3V3_STBY ; 2 = PU_JTAG_BMC_RTCK
R25W106  RES  4.75K 1% EMPTY  pkg 0402  page 150 : 1 = P3V3_STBY ; 2 = RMII_BMC_OCP_TXEN
R25W107  RES  4.75K 1% CHIP  pkg 0402  page 150 : 1 = P3V3_STBY ; 2 = RMII_BMC_OCP_TXD0_R
R25W108  RES  4.75K 1% EMPTY  pkg 0402  page 150 : 1 = P3V3_STBY ; 2 = RMII_BMC_OCP_TXD1_R
R25W109  RES  4.75K 1% CHIP  pkg 0402  page 150 : 1 = P3V3_STBY ; 2 = TP_RGMII2TXD3_GPIOU3
R25W110  RES  4.75K 1% EMPTY  pkg 0402  page 150 : 1 = P3V3_STBY ; 2 = TP_RGMII2TXD2_GPIOU2
R25W111  RES  4.75K 1% EMPTY  pkg 0402  page 150 : 1 = P3V3_STBY ; 2 = RMII_BMC_PCH_SPRNGVLLE_TXEN
R25W112  RES  4.75K 1% EMPTY  pkg 0402  page 150 : 1 = P3V3_STBY ; 2 = RMII_BMC_PCH_SPRNGVLLE_TXD0_R
R25W113  RES  4.75K 1% EMPTY  pkg 0402  page 150 : 1 = P3V3_STBY ; 2 = RMII_BMC_PCH_SPRNGVLLE_TXD1_R
R25W114  RES  4.75K 1% EMPTY  pkg 0402  page 150 : 1 = P3V3_STBY ; 2 = TP_RGMII1TXD2_GPIOT4
R25W115  RES  4.75K 1% EMPTY  pkg 0402  page 150 : 1 = P3V3_STBY ; 2 = TP_RGMII1TXD3_GPIOT5
R25W116  RES  3.32K 1% EMPTY  pkg 0402  page 150 : 1 = GND ; 2 = UART_BMC_TXD5
R25W117  RES  240 1.0% CHIP  pkg 0402  page 151 : 1 = BMC_ZQ ; 2 = GND
R25W118  RES  0.0 5% CHIP  pkg 0402  page 151 : 1 = BMC_M_PAR ; 2 = GND
R25W119  RES  4.75K 1% EMPTY  pkg 0402  page 151 : 1 = P1V2_AUX_BMC ; 2 = BMC_M_PAR
R25W120  RES  0 5.0% CHIP  pkg 0603  page 149 : 1 = P3V3_STBY ; 2 = P3V3_USB2A_ALG
R25W121  RES  20.0 1% CHIP  pkg 0402  page 145 : 1 = SMB_PEHPCPU0_STBY_LVC3_R_SDA ; 2 = SMB_PEHPCPU0_STBY_LVC3_R2_SDA
R25W122  RES  20.0 1% CHIP  pkg 0402  page 145 : 1 = SMB_PEHPCPU0_STBY_LVC3_R_SCL ; 2 = SMB_PEHPCPU0_STBY_LVC3_R2_SCL
R25W123  RES  150.0 1% CHIP  pkg 0402  page 144 : 1 = BMC_VGA_BLUE ; 2 = GND
R25W124  RES  150.0 1% CHIP  pkg 0402  page 144 : 1 = BMC_VGA_GREEN ; 2 = GND
R25W125  RES  150.0 1% CHIP  pkg 0402  page 144 : 1 = BMC_VGA_RED ; 2 = GND
R25W126  RES  150.0 1% CHIP  pkg 0402  page 252 : 1 = V_IO_B_J ; 2 = GND
R25W127  RES  150.0 1% CHIP  pkg 0402  page 252 : 1 = V_IO_G_J ; 2 = GND
R25W128  RES  150.0 1% CHIP  pkg 0402  page 252 : 1 = V_IO_R_J ; 2 = GND
R25W129  RES  4.75K 1% CHIP  pkg 0402  page 146 : 1 = P3V3 ; 2 = I2C_BMC_VGA_DDC_SCL
R25W130  RES  4.75K 1% CHIP  pkg 0402  page 146 : 1 = P3V3 ; 2 = I2C_BMC_VGA_DDC_SDA
R25W131  RES  4.75K 1% CHIP  pkg 0402  page 252 : 1 = P3V3 ; 2 = Q25W1_GATE
R25W132  RES  4.75K 1% CHIP  pkg 0402  page 252 : 1 = P5V_VGA_D ; 2 = I2C_BMC_VGA_DDC_SCL_G
R25W133  RES  33.2 1% CHIP  pkg 0402  page 252 : 1 = I2C_BMC_VGA_DDC_SCL_G ; 2 = V_IBMC_5V_DDC_SCL_J
R25W134  RES  4.75K 1% CHIP  pkg 0402  page 252 : 1 = P3V3 ; 2 = Q25W2_GATE
R25W135  RES  4.75K 1% CHIP  pkg 0402  page 252 : 1 = P5V_VGA_D ; 2 = I2C_BMC_VGA_DDC_SDA_G
R25W136  RES  33.2 1% CHIP  pkg 0402  page 252 : 1 = I2C_BMC_VGA_DDC_SDA_G ; 2 = V_IBMC_5V_DDC_SDA_J
R25W138  RES  33.2 1% CHIP  pkg 0402  page 252 : 1 = VGA_REAR_HSYNC_S ; 2 = V_IO_HSYNC_J
R25W139  RES  33.2 1% CHIP  pkg 0402  page 252 : 1 = VGA_REAR_VSYNC_S ; 2 = V_IO_VSYNC_J
R25W140  RES  0.0 5% EMPTY  pkg 0402  page 144 : 1 = CLK_48M_USB_BMC ; 2 = CLK_48M_USB_BMC_R
R25W141  RES  0.0 5% CHIP  pkg 0402  page 145 : 1 = RST_PLTRST_BUF_N ; 2 = RST_PLTRST_BUF_N_R
R25W142  RES  100.0K 1% CHIP  pkg 0402  page 147 : 1 = PUMP_TACH1 ; 2 = GND
R25W143  RES  0.0 5% CHIP  pkg 0402  page 147 : 1 = FM_GLOBAL_RST_WARN_N_R ; 2 = FM_GLOBAL_RST_WARN_N
R25W144  RES  0.0 5% CHIP  pkg 0402  page 145 : 1 = FM_PWR_BTN_R1_N ; 2 = FM_PWR_BTN_N
R25W145  RES  0.0 5% CHIP  pkg 0402  page 145 : 1 = RST_SYSTEM_BTN_R_N ; 2 = RST_SYSTEM_BTN_N
R25W146  RES  4.75K 1% CHIP  pkg 0402  page 150 : 1 = GND ; 2 = RMII_BMC_OCP_TXEN
R25W148  RES  4.75K 1% CHIP  pkg 0402  page 150 : 1 = GND ; 2 = RMII_BMC_OCP_TXD1_R
R25W149  RES  4.75K 1% CHIP  pkg 0402  page 150 : 1 = GND ; 2 = TP_RGMII1TXD2_GPIOT4
R25W150  RES  4.75K 1% CHIP  pkg 0402  page 150 : 1 = GND ; 2 = RMII_BMC_PCH_SPRNGVLLE_TXD0_R
R25W151  RES  4.75K 1% CHIP  pkg 0402  page 150 : 1 = GND ; 2 = RMII_BMC_PCH_SPRNGVLLE_TXD1_R
R25W152  RES  4.75K 1% CHIP  pkg 0402  page 150 : 1 = GND ; 2 = TP_RGMII2TXD2_GPIOU2
R25W153  RES  4.75K 1% CHIP  pkg 0402  page 157 : 1 = P3V3_STBY ; 2 = RST_BMC_SRST_N
R25W154  RES  0.0 5% CHIP  pkg 0402  page 137 : 1 = SPI_BMC_BT_WP0_N ; 2 = TPM_SPI_BMC_WP_N
R25W155  RES  0.0 5% CHIP  pkg 0402  page 148 : 1 = PVCCIO_CPU0 ; 2 = PVCCIO_CPU0_R
R25W156  RES  3.32K 1% EMPTY  pkg 0402  page 150 : 1 = P3V3_STBY ; 2 = UART_BMC_TXD5
R25W157  RES  100.0K 1% CHIP  pkg 0402  page 147 : 1 = PUMP_TACH0 ; 2 = GND
R25W158  RES  1.00K 1% CHIP  pkg 0402  page 254 : 1 = P3V3_STBY ; 2 = PU_GTL2014_3_DIR
R25W159  RES  1.00K 1% CHIP  pkg 0402  page 254 : 1 = GND ; 2 = PD_GTL2014_3_VREF
R25W160  RES  1.00K 1% CHIP  pkg 0402  page 254 : 1 = P3V3_STBY ; 2 = JTAG_BMC_BUF_TDI
R25W161  RES  1.00K 1% CHIP  pkg 0402  page 254 : 1 = P3V3_STBY ; 2 = JTAG_BMC_BUF_TMS
R25W164  RES  49.9 1% CHIP  pkg 0402  page 255 : 1 = P1V05_PCH_STBY ; 2 = P0V7_GTL2014_VREF_6
R25W165  RES  100.0 1% CHIP  pkg 0402  page 255 : 1 = P0V7_GTL2014_VREF_6 ; 2 = GND
R25W166  RES  1.00K 1% CHIP  pkg 0402  page 255 : 1 = PD_GTL2014_DIR_6 ; 2 = GND
R25W167  RES  1.00K 1% CHIP  pkg 0402  page 254 : 1 = BMC_TCK_MUX_SEL ; 2 = GND
R25W168  RES  1.00K 1% CHIP  pkg 0402  page 254 : 1 = JTAG_BMC_TCK0 ; 2 = GND
R25W169  RES  1.00K 1% CHIP  pkg 0402  page 254 : 1 = JTAG_BMC_TCK1 ; 2 = GND
R25W170  RES  1.00K 1% CHIP  pkg 0402  page 254 : 1 = JTAG_BMC_TRST_BUF_N ; 2 = GND
R25W174  RES  10.0K 1% CHIP  pkg 0402  page 254 : 1 = P3V3_STBY ; 2 = BMC_JTAG_SEL_N
R25W175  RES  1.00K 1% CHIP  pkg 0402  page 255 : 1 = PD_GTL2014_6_B0 ; 2 = GND
R25W176  RES  1.00K 1% CHIP  pkg 0402  page 255 : 1 = PD_GTL2014_6_B2 ; 2 = GND
R25W177  RES  1.00K 1% CHIP  pkg 0402  page 254 : 1 = P3V3_STBY ; 2 = BMC_PREQ_BUF_N
R25W178  RES  1.00K 1% CHIP  pkg 0402  page 254 : 1 = P3V3_STBY ; 2 = BMC_PWR_DEBUG_BUF_N
R25W179  RES  1.00K 1% CHIP  pkg 0402  page 255 : 1 = P3V3_STBY ; 2 = XDP_PRESENT_N
R25W180  RES  1.00K 1% CHIP  pkg 0402  page 255 : 1 = P3V3_STBY ; 2 = BMC_DEBUG_EN_N
R25W181  RES  0.0 5% CHIP  pkg 0402  page 147 : 1 = RST_RSMRST_N ; 2 = BMC_RSMRST_B_N
R25W182  RES  0.0 5% CHIP  pkg 0402  page 144 : 1 = XDP_SYSPWROK ; 2 = PWRGD_SYS_PWROK
